(kicad_pcb
	(version 20260206)
	(generator "pcbnew")
	(generator_version "10.0")
	(general
		(thickness 1.6)
		(legacy_teardrops no)
	)
	(paper "A4")
	(title_block
		(title "03242023_DA0F0TMBIJ0_F0T_Motherboard_J_brd_V01_OCP.brd")
		(comment 1 "Grand Teton / footprints 5368-5373 of 6105")
	)
	(layers
		(0 "F.Cu" signal "TOP")
		(4 "In1.Cu" signal "GND")
		(6 "In2.Cu" signal "IN1")
		(8 "In3.Cu" signal "GND1")
		(10 "In4.Cu" signal "IN2")
		(12 "In5.Cu" signal "GND2")
		(14 "In6.Cu" signal "IN3")
		(16 "In7.Cu" signal "GND3")
		(18 "In8.Cu" signal "VCC")
		(20 "In9.Cu" signal "VCC1")
		(22 "In10.Cu" signal "GND4")
		(24 "In11.Cu" signal "IN4")
		(26 "In12.Cu" signal "GND5")
		(28 "In13.Cu" signal "IN5")
		(30 "In14.Cu" signal "GND6")
		(32 "In15.Cu" signal "IN6")
		(34 "In16.Cu" signal "GND7")
		(2 "B.Cu" signal "BOTTOM")
		(9 "F.Adhes" user "F.Adhesive")
		(11 "B.Adhes" user "B.Adhesive")
		(13 "F.Paste" user "Package Geometry/Pastemask Top")
		(15 "B.Paste" user "Package Geometry/Pastemask Bottom")
		(5 "F.SilkS" user "Ref Des/Silkscreen Top")
		(7 "B.SilkS" user "Ref Des/Silkscreen Bottom")
		(1 "F.Mask" user "Board Geometry/Soldermask Top")
		(3 "B.Mask" user "Board Geometry/Soldermask Bottom")
		(17 "Dwgs.User" user "User.Drawings")
		(19 "Cmts.User" user "User.Comments")
		(21 "Eco1.User" user "User.Eco1")
		(23 "Eco2.User" user "User.Eco2")
		(25 "Edge.Cuts" user "Board Geometry/Outline")
		(27 "Margin" user)
		(31 "F.CrtYd" user "Package Geometry/Place Bound Top")
		(29 "B.CrtYd" user "Package Geometry/Place Bound Bottom")
		(35 "F.Fab" user "Ref Des/Assembly Top")
		(33 "B.Fab" user "Ref Des/Assembly Bottom")
	)
	(footprint ""
		(layer "B.Cu")
		(at 173.913546 -319.268856 180)
		(property "Reference" "C84"
			(at 0 0 0)
			(layer "B.SilkS")
			(hide yes)
			(effects
				(font
					(size 1.27 1.27)
				)
				(justify mirror)
			)
		)
		(property "Value" ""
			(at 0 0 0)
			(layer "B.Fab")
			(effects
				(font
					(size 1.27 1.27)
				)
				(justify mirror)
			)
		)
		(duplicate_pad_numbers_are_jumpers no)
		(fp_line
			(start 0.7874 0.4064)
			(end 0.7874 -0.4064)
			(stroke
				(width 0.1524)
				(type default)
			)
			(layer "B.SilkS")
		)
		(fp_line
			(start 0.7874 -0.4064)
			(end -0.7874 -0.4064)
			(stroke
				(width 0.1524)
				(type default)
			)
			(layer "B.SilkS")
		)
		(fp_line
			(start -0.7874 0.4064)
			(end 0.7874 0.4064)
			(stroke
				(width 0.1524)
				(type default)
			)
			(layer "B.SilkS")
		)
		(fp_line
			(start -0.7874 -0.4064)
			(end -0.7874 0.4064)
			(stroke
				(width 0.1524)
				(type default)
			)
			(layer "B.SilkS")
		)
		(fp_line
			(start 0.67945 0.3048)
			(end 0.67945 -0.305054)
			(stroke
				(width 0.1)
				(type default)
			)
			(layer "B.Fab")
		)
		(fp_line
			(start 0.67945 -0.305054)
			(end 0.12065 -0.305054)
			(stroke
				(width 0.1)
				(type default)
			)
			(layer "B.Fab")
		)
		(fp_line
			(start 0.12065 0.3048)
			(end 0.67945 0.3048)
			(stroke
				(width 0.1)
				(type default)
			)
			(layer "B.Fab")
		)
		(fp_line
			(start 0.12065 0.2794)
			(end 0.12065 0.3048)
			(stroke
				(width 0.1)
				(type default)
			)
			(layer "B.Fab")
		)
		(fp_line
			(start 0.12065 -0.2794)
			(end -0.12065 -0.2794)
			(stroke
				(width 0.1)
				(type default)
			)
			(layer "B.Fab")
		)
		(fp_line
			(start 0.12065 -0.305054)
			(end 0.12065 -0.2794)
			(stroke
				(width 0.1)
				(type default)
			)
			(layer "B.Fab")
		)
		(fp_line
			(start -0.120396 0.3048)
			(end -0.120396 0.2794)
			(stroke
				(width 0.1)
				(type default)
			)
			(layer "B.Fab")
		)
		(fp_line
			(start -0.120396 0.2794)
			(end 0.12065 0.2794)
			(stroke
				(width 0.1)
				(type default)
			)
			(layer "B.Fab")
		)
		(fp_line
			(start -0.12065 -0.2794)
			(end -0.12065 -0.3048)
			(stroke
				(width 0.1)
				(type default)
			)
			(layer "B.Fab")
		)
		(fp_line
			(start -0.12065 -0.3048)
			(end -0.67945 -0.3048)
			(stroke
				(width 0.1)
				(type default)
			)
			(layer "B.Fab")
		)
		(fp_line
			(start -0.67945 0.3048)
			(end -0.120396 0.3048)
			(stroke
				(width 0.1)
				(type default)
			)
			(layer "B.Fab")
		)
		(fp_line
			(start -0.67945 -0.3048)
			(end -0.67945 0.3048)
			(stroke
				(width 0.1)
				(type default)
			)
			(layer "B.Fab")
		)
		(pad "1" smd circle
			(at 0.40005 0)
			(size 0 0)
			(layers "B.Cu" "B.Mask" "B.Paste")
			(net "P3V3_AUX")
		)
		(pad "2" smd circle
			(at -0.40005 0)
			(size 0 0)
			(layers "B.Cu" "B.Mask" "B.Paste")
			(net "GND")
		)
	)
	(footprint ""
		(layer "B.Cu")
		(at 156.1465 -190.99911 90)
		(property "Reference" "R1217"
			(at 0 0 90)
			(layer "B.SilkS")
			(hide yes)
			(effects
				(font
					(size 1.27 1.27)
				)
				(justify mirror)
			)
		)
		(property "Value" ""
			(at 0 0 90)
			(layer "B.Fab")
			(effects
				(font
					(size 1.27 1.27)
				)
				(justify mirror)
			)
		)
		(duplicate_pad_numbers_are_jumpers no)
		(fp_line
			(start 0.7874 -0.4064)
			(end -0.7874 -0.4064)
			(stroke
				(width 0.1524)
				(type default)
			)
			(layer "B.SilkS")
		)
		(fp_line
			(start -0.7874 -0.4064)
			(end -0.7874 0.4064)
			(stroke
				(width 0.1524)
				(type default)
			)
			(layer "B.SilkS")
		)
		(fp_line
			(start 0.7874 0.4064)
			(end 0.7874 -0.4064)
			(stroke
				(width 0.1524)
				(type default)
			)
			(layer "B.SilkS")
		)
		(fp_line
			(start -0.7874 0.4064)
			(end 0.7874 0.4064)
			(stroke
				(width 0.1524)
				(type default)
			)
			(layer "B.SilkS")
		)
		(fp_line
			(start 0.67945 -0.305054)
			(end 0.12065 -0.305054)
			(stroke
				(width 0.1)
				(type default)
			)
			(layer "B.Fab")
		)
		(fp_line
			(start 0.12065 -0.305054)
			(end 0.12065 -0.2794)
			(stroke
				(width 0.1)
				(type default)
			)
			(layer "B.Fab")
		)
		(fp_line
			(start -0.12065 -0.3048)
			(end -0.67945 -0.3048)
			(stroke
				(width 0.1)
				(type default)
			)
			(layer "B.Fab")
		)
		(fp_line
			(start -0.67945 -0.3048)
			(end -0.67945 0.3048)
			(stroke
				(width 0.1)
				(type default)
			)
			(layer "B.Fab")
		)
		(fp_line
			(start 0.12065 -0.2794)
			(end -0.12065 -0.2794)
			(stroke
				(width 0.1)
				(type default)
			)
			(layer "B.Fab")
		)
		(fp_line
			(start -0.12065 -0.2794)
			(end -0.12065 -0.3048)
			(stroke
				(width 0.1)
				(type default)
			)
			(layer "B.Fab")
		)
		(fp_line
			(start 0.12065 0.2794)
			(end 0.12065 0.3048)
			(stroke
				(width 0.1)
				(type default)
			)
			(layer "B.Fab")
		)
		(fp_line
			(start -0.120396 0.2794)
			(end 0.12065 0.2794)
			(stroke
				(width 0.1)
				(type default)
			)
			(layer "B.Fab")
		)
		(fp_line
			(start 0.67945 0.3048)
			(end 0.67945 -0.305054)
			(stroke
				(width 0.1)
				(type default)
			)
			(layer "B.Fab")
		)
		(fp_line
			(start 0.12065 0.3048)
			(end 0.67945 0.3048)
			(stroke
				(width 0.1)
				(type default)
			)
			(layer "B.Fab")
		)
		(fp_line
			(start -0.120396 0.3048)
			(end -0.120396 0.2794)
			(stroke
				(width 0.1)
				(type default)
			)
			(layer "B.Fab")
		)
		(fp_line
			(start -0.67945 0.3048)
			(end -0.120396 0.3048)
			(stroke
				(width 0.1)
				(type default)
			)
			(layer "B.Fab")
		)
		(pad "1" smd circle
			(at 0.40005 0 270)
			(size 0 0)
			(layers "B.Cu" "B.Mask" "B.Paste")
			(net "P3V3_AUX")
		)
		(pad "2" smd circle
			(at -0.40005 0 270)
			(size 0 0)
			(layers "B.Cu" "B.Mask" "B.Paste")
			(net "FM_S3M_CPU1_CPLD_CRC_ERROR")
		)
	)
	(footprint ""
		(layer "B.Cu")
		(at 294.71874 -413.95904 90)
		(property "Reference" "R4691"
			(at 0 0 90)
			(layer "B.SilkS")
			(hide yes)
			(effects
				(font
					(size 1.27 1.27)
				)
				(justify mirror)
			)
		)
		(property "Value" ""
			(at 0 0 90)
			(layer "B.Fab")
			(effects
				(font
					(size 1.27 1.27)
				)
				(justify mirror)
			)
		)
		(duplicate_pad_numbers_are_jumpers no)
		(fp_line
			(start 0.7874 -0.4064)
			(end -0.7874 -0.4064)
			(stroke
				(width 0.1524)
				(type default)
			)
			(layer "B.SilkS")
		)
		(fp_line
			(start -0.7874 -0.4064)
			(end -0.7874 0.4064)
			(stroke
				(width 0.1524)
				(type default)
			)
			(layer "B.SilkS")
		)
		(fp_line
			(start 0.7874 0.4064)
			(end 0.7874 -0.4064)
			(stroke
				(width 0.1524)
				(type default)
			)
			(layer "B.SilkS")
		)
		(fp_line
			(start -0.7874 0.4064)
			(end 0.7874 0.4064)
			(stroke
				(width 0.1524)
				(type default)
			)
			(layer "B.SilkS")
		)
		(fp_line
			(start 0.67945 -0.305054)
			(end 0.12065 -0.305054)
			(stroke
				(width 0.1)
				(type default)
			)
			(layer "B.Fab")
		)
		(fp_line
			(start 0.12065 -0.305054)
			(end 0.12065 -0.2794)
			(stroke
				(width 0.1)
				(type default)
			)
			(layer "B.Fab")
		)
		(fp_line
			(start -0.12065 -0.3048)
			(end -0.67945 -0.3048)
			(stroke
				(width 0.1)
				(type default)
			)
			(layer "B.Fab")
		)
		(fp_line
			(start -0.67945 -0.3048)
			(end -0.67945 0.3048)
			(stroke
				(width 0.1)
				(type default)
			)
			(layer "B.Fab")
		)
		(fp_line
			(start 0.12065 -0.2794)
			(end -0.12065 -0.2794)
			(stroke
				(width 0.1)
				(type default)
			)
			(layer "B.Fab")
		)
		(fp_line
			(start -0.12065 -0.2794)
			(end -0.12065 -0.3048)
			(stroke
				(width 0.1)
				(type default)
			)
			(layer "B.Fab")
		)
		(fp_line
			(start 0.12065 0.2794)
			(end 0.12065 0.3048)
			(stroke
				(width 0.1)
				(type default)
			)
			(layer "B.Fab")
		)
		(fp_line
			(start -0.120396 0.2794)
			(end 0.12065 0.2794)
			(stroke
				(width 0.1)
				(type default)
			)
			(layer "B.Fab")
		)
		(fp_line
			(start 0.67945 0.3048)
			(end 0.67945 -0.305054)
			(stroke
				(width 0.1)
				(type default)
			)
			(layer "B.Fab")
		)
		(fp_line
			(start 0.12065 0.3048)
			(end 0.67945 0.3048)
			(stroke
				(width 0.1)
				(type default)
			)
			(layer "B.Fab")
		)
		(fp_line
			(start -0.120396 0.3048)
			(end -0.120396 0.2794)
			(stroke
				(width 0.1)
				(type default)
			)
			(layer "B.Fab")
		)
		(fp_line
			(start -0.67945 0.3048)
			(end -0.120396 0.3048)
			(stroke
				(width 0.1)
				(type default)
			)
			(layer "B.Fab")
		)
		(pad "1" smd circle
			(at 0.40005 0 270)
			(size 0 0)
			(layers "B.Cu" "B.Mask" "B.Paste")
			(net "HSC_TYPE_ADC_A0")
		)
		(pad "2" smd circle
			(at -0.40005 0 270)
			(size 0 0)
			(layers "B.Cu" "B.Mask" "B.Paste")
			(net "SMB_HSC_TYPE_ADC_SDA")
		)
	)
	(footprint ""
		(layer "B.Cu")
		(at 356.785418 -294.009826 180)
		(property "Reference" "C372"
			(at 0 0 0)
			(layer "B.SilkS")
			(hide yes)
			(effects
				(font
					(size 1.27 1.27)
				)
				(justify mirror)
			)
		)
		(property "Value" ""
			(at 0 0 0)
			(layer "B.Fab")
			(effects
				(font
					(size 1.27 1.27)
				)
				(justify mirror)
			)
		)
		(duplicate_pad_numbers_are_jumpers no)
		(fp_line
			(start 1.524 0.762)
			(end 1.524 -0.762)
			(stroke
				(width 0.1524)
				(type default)
			)
			(layer "B.SilkS")
		)
		(fp_line
			(start 1.524 -0.762)
			(end -1.524 -0.762)
			(stroke
				(width 0.1524)
				(type default)
			)
			(layer "B.SilkS")
		)
		(fp_line
			(start -1.524 0.762)
			(end 1.524 0.762)
			(stroke
				(width 0.1524)
				(type default)
			)
			(layer "B.SilkS")
		)
		(fp_line
			(start -1.524 -0.762)
			(end -1.524 0.762)
			(stroke
				(width 0.1524)
				(type default)
			)
			(layer "B.SilkS")
		)
		(fp_line
			(start 1.1049 0.724916)
			(end -1.1049 0.724916)
			(stroke
				(width 0.1)
				(type default)
			)
			(layer "B.Fab")
		)
		(fp_line
			(start 1.1049 -0.724916)
			(end 1.1049 0.724916)
			(stroke
				(width 0.1)
				(type default)
			)
			(layer "B.Fab")
		)
		(fp_line
			(start -1.1049 0.724916)
			(end -1.1049 -0.724916)
			(stroke
				(width 0.1)
				(type default)
			)
			(layer "B.Fab")
		)
		(fp_line
			(start -1.1049 -0.724916)
			(end 1.1049 -0.724916)
			(stroke
				(width 0.1)
				(type default)
			)
			(layer "B.Fab")
		)
		(pad "1" smd rect
			(at 0.889 0 180)
			(size 1.016 1.27)
			(layers "B.Cu" "B.Mask" "B.Paste")
			(net "PVCCIN_CPU0")
		)
		(pad "2" smd rect
			(at -0.889 0 180)
			(size 1.016 1.27)
			(layers "B.Cu" "B.Mask" "B.Paste")
			(net "GND")
		)
	)
	(footprint ""
		(layer "B.Cu")
		(at 235.955332 -123.453652 90)
		(property "Reference" "C211"
			(at 0 0 90)
			(layer "B.SilkS")
			(hide yes)
			(effects
				(font
					(size 1.27 1.27)
				)
				(justify mirror)
			)
		)
		(property "Value" ""
			(at 0 0 90)
			(layer "B.Fab")
			(effects
				(font
					(size 1.27 1.27)
				)
				(justify mirror)
			)
		)
		(duplicate_pad_numbers_are_jumpers no)
		(fp_line
			(start 0.7874 -0.4064)
			(end -0.7874 -0.4064)
			(stroke
				(width 0.1524)
				(type default)
			)
			(layer "B.SilkS")
		)
		(fp_line
			(start -0.7874 -0.4064)
			(end -0.7874 0.4064)
			(stroke
				(width 0.1524)
				(type default)
			)
			(layer "B.SilkS")
		)
		(fp_line
			(start 0.7874 0.4064)
			(end 0.7874 -0.4064)
			(stroke
				(width 0.1524)
				(type default)
			)
			(layer "B.SilkS")
		)
		(fp_line
			(start -0.7874 0.4064)
			(end 0.7874 0.4064)
			(stroke
				(width 0.1524)
				(type default)
			)
			(layer "B.SilkS")
		)
		(fp_line
			(start 0.67945 -0.305054)
			(end 0.12065 -0.305054)
			(stroke
				(width 0.1)
				(type default)
			)
			(layer "B.Fab")
		)
		(fp_line
			(start 0.12065 -0.305054)
			(end 0.12065 -0.2794)
			(stroke
				(width 0.1)
				(type default)
			)
			(layer "B.Fab")
		)
		(fp_line
			(start -0.12065 -0.3048)
			(end -0.67945 -0.3048)
			(stroke
				(width 0.1)
				(type default)
			)
			(layer "B.Fab")
		)
		(fp_line
			(start -0.67945 -0.3048)
			(end -0.67945 0.3048)
			(stroke
				(width 0.1)
				(type default)
			)
			(layer "B.Fab")
		)
		(fp_line
			(start 0.12065 -0.2794)
			(end -0.12065 -0.2794)
			(stroke
				(width 0.1)
				(type default)
			)
			(layer "B.Fab")
		)
		(fp_line
			(start -0.12065 -0.2794)
			(end -0.12065 -0.3048)
			(stroke
				(width 0.1)
				(type default)
			)
			(layer "B.Fab")
		)
		(fp_line
			(start 0.12065 0.2794)
			(end 0.12065 0.3048)
			(stroke
				(width 0.1)
				(type default)
			)
			(layer "B.Fab")
		)
		(fp_line
			(start -0.120396 0.2794)
			(end 0.12065 0.2794)
			(stroke
				(width 0.1)
				(type default)
			)
			(layer "B.Fab")
		)
		(fp_line
			(start 0.67945 0.3048)
			(end 0.67945 -0.305054)
			(stroke
				(width 0.1)
				(type default)
			)
			(layer "B.Fab")
		)
		(fp_line
			(start 0.12065 0.3048)
			(end 0.67945 0.3048)
			(stroke
				(width 0.1)
				(type default)
			)
			(layer "B.Fab")
		)
		(fp_line
			(start -0.120396 0.3048)
			(end -0.120396 0.2794)
			(stroke
				(width 0.1)
				(type default)
			)
			(layer "B.Fab")
		)
		(fp_line
			(start -0.67945 0.3048)
			(end -0.120396 0.3048)
			(stroke
				(width 0.1)
				(type default)
			)
			(layer "B.Fab")
		)
		(pad "1" smd circle
			(at 0.40005 0 270)
			(size 0 0)
			(layers "B.Cu" "B.Mask" "B.Paste")
			(net "P3V3_DB2000_VDDA")
		)
		(pad "2" smd circle
			(at -0.40005 0 270)
			(size 0 0)
			(layers "B.Cu" "B.Mask" "B.Paste")
			(net "GND")
		)
	)
	(footprint ""
		(layer "B.Cu")
		(at 134.347966 -345.463114 -90)
		(property "Reference" "PR289"
			(at 0 0 90)
			(layer "B.SilkS")
			(hide yes)
			(effects
				(font
					(size 1.27 1.27)
				)
				(justify mirror)
			)
		)
		(property "Value" ""
			(at 0 0 90)
			(layer "B.Fab")
			(effects
				(font
					(size 1.27 1.27)
				)
				(justify mirror)
			)
		)
		(duplicate_pad_numbers_are_jumpers no)
		(fp_line
			(start -0.7874 0.4064)
			(end 0.7874 0.4064)
			(stroke
				(width 0.1524)
				(type default)
			)
			(layer "B.SilkS")
		)
		(fp_line
			(start 0.7874 0.4064)
			(end 0.7874 -0.4064)
			(stroke
				(width 0.1524)
				(type default)
			)
			(layer "B.SilkS")
		)
		(fp_line
			(start -0.7874 -0.4064)
			(end -0.7874 0.4064)
			(stroke
				(width 0.1524)
				(type default)
			)
			(layer "B.SilkS")
		)
		(fp_line
			(start 0.7874 -0.4064)
			(end -0.7874 -0.4064)
			(stroke
				(width 0.1524)
				(type default)
			)
			(layer "B.SilkS")
		)
		(fp_line
			(start -0.67945 0.3048)
			(end -0.120396 0.3048)
			(stroke
				(width 0.1)
				(type default)
			)
			(layer "B.Fab")
		)
		(fp_line
			(start -0.120396 0.3048)
			(end -0.120396 0.2794)
			(stroke
				(width 0.1)
				(type default)
			)
			(layer "B.Fab")
		)
		(fp_line
			(start 0.12065 0.3048)
			(end 0.67945 0.3048)
			(stroke
				(width 0.1)
				(type default)
			)
			(layer "B.Fab")
		)
		(fp_line
			(start 0.67945 0.3048)
			(end 0.67945 -0.305054)
			(stroke
				(width 0.1)
				(type default)
			)
			(layer "B.Fab")
		)
		(fp_line
			(start -0.120396 0.2794)
			(end 0.12065 0.2794)
			(stroke
				(width 0.1)
				(type default)
			)
			(layer "B.Fab")
		)
		(fp_line
			(start 0.12065 0.2794)
			(end 0.12065 0.3048)
			(stroke
				(width 0.1)
				(type default)
			)
			(layer "B.Fab")
		)
		(fp_line
			(start -0.12065 -0.2794)
			(end -0.12065 -0.3048)
			(stroke
				(width 0.1)
				(type default)
			)
			(layer "B.Fab")
		)
		(fp_line
			(start 0.12065 -0.2794)
			(end -0.12065 -0.2794)
			(stroke
				(width 0.1)
				(type default)
			)
			(layer "B.Fab")
		)
		(fp_line
			(start -0.67945 -0.3048)
			(end -0.67945 0.3048)
			(stroke
				(width 0.1)
				(type default)
			)
			(layer "B.Fab")
		)
		(fp_line
			(start -0.12065 -0.3048)
			(end -0.67945 -0.3048)
			(stroke
				(width 0.1)
				(type default)
			)
			(layer "B.Fab")
		)
		(fp_line
			(start 0.12065 -0.305054)
			(end 0.12065 -0.2794)
			(stroke
				(width 0.1)
				(type default)
			)
			(layer "B.Fab")
		)
		(fp_line
			(start 0.67945 -0.305054)
			(end 0.12065 -0.305054)
			(stroke
				(width 0.1)
				(type default)
			)
			(layer "B.Fab")
		)
		(pad "1" smd circle
			(at 0.40005 0 90)
			(size 0 0)
			(layers "B.Cu" "B.Mask" "B.Paste")
			(net "PVCCIN_CPU1_VOS8")
		)
		(pad "2" smd circle
			(at -0.40005 0 90)
			(size 0 0)
			(layers "B.Cu" "B.Mask" "B.Paste")
			(net "PVCCIN_CPU1")
		)
	)
)
